(kicad_pcb
	(version 20241229)
	(generator "pcbnew")
	(generator_version "9.0")
	(general
		(thickness 1.6)
		(legacy_teardrops no)
	)
	(paper "A4")
	(title_block
		(title "GMSL Deserializer")
		(date "2025-10-09")
		(rev "1.0.4")
		(company "Antmicro Ltd")
		(comment 1 "www.antmicro.com")
		(comment 9 "footprints 212-217 of 235")
	)
	(layers
		(0 "F.Cu" signal)
		(4 "In1.Cu" power)
		(6 "In2.Cu" power)
		(2 "B.Cu" signal)
		(9 "F.Adhes" user "F.Adhesive")
		(11 "B.Adhes" user "B.Adhesive")
		(13 "F.Paste" user)
		(15 "B.Paste" user)
		(5 "F.SilkS" user "F.Silkscreen")
		(7 "B.SilkS" user "B.Silkscreen")
		(1 "F.Mask" user)
		(3 "B.Mask" user)
		(17 "Dwgs.User" user "User.Drawings")
		(19 "Cmts.User" user "User.Comments")
		(21 "Eco1.User" user "User.Eco1")
		(23 "Eco2.User" user "User.Eco2")
		(25 "Edge.Cuts" user)
		(27 "Margin" user)
		(31 "F.CrtYd" user "F.Courtyard")
		(29 "B.CrtYd" user "B.Courtyard")
		(35 "F.Fab" user)
		(33 "B.Fab" user)
	)
	(footprint "antmicro-footprints:TP_SMD_0.75mm"
		(layer "B.Cu")
		(at 142.748 97.78 180)
		(property "Reference" "TP26"
			(at 0 0.6 0)
			(layer "B.SilkS")
			(hide yes)
			(effects
				(font
					(size 0.7 0.7)
					(thickness 0.15)
				)
				(justify left bottom mirror)
			)
		)
		(property "Value" "TP_0.75mm_SMD"
			(at 0 -1.2 0)
			(layer "B.Fab")
			(effects
				(font
					(size 0.7 0.7)
					(thickness 0.15)
				)
				(justify left bottom mirror)
			)
		)
		(property "Description" "SMT test point"
			(at 0 0 0)
			(layer "B.Fab")
			(hide yes)
			(effects
				(font
					(size 1.27 1.27)
					(thickness 0.15)
				)
				(justify mirror)
			)
		)
		(property "MPN" ""
			(at 0 0 0)
			(unlocked yes)
			(layer "B.Fab")
			(hide yes)
			(effects
				(font
					(size 1 1)
					(thickness 0.15)
				)
				(justify mirror)
			)
		)
		(property "Manufacturer" ""
			(at 0 0 0)
			(unlocked yes)
			(layer "B.Fab")
			(hide yes)
			(effects
				(font
					(size 1 1)
					(thickness 0.15)
				)
				(justify mirror)
			)
		)
		(property "Author" "Antmicro"
			(at 0 0 0)
			(unlocked yes)
			(layer "B.Fab")
			(hide yes)
			(effects
				(font
					(size 1 1)
					(thickness 0.15)
				)
				(justify mirror)
			)
		)
		(property "License" "Apache-2.0"
			(at 0 0 0)
			(unlocked yes)
			(layer "B.Fab")
			(hide yes)
			(effects
				(font
					(size 1 1)
					(thickness 0.15)
				)
				(justify mirror)
			)
		)
		(sheetname "/Power/")
		(sheetfile "power.kicad_sch")
		(attr exclude_from_pos_files)
		(fp_circle
			(center 0 0)
			(end 0.475 0)
			(stroke
				(width 0.05)
				(type default)
			)
			(fill no)
			(layer "B.CrtYd")
		)
		(fp_text user "${REFERENCE}"
			(at -0.4 -2.7 0)
			(layer "B.Fab")
			(effects
				(font
					(size 0.7 0.7)
					(thickness 0.15)
				)
				(justify left bottom mirror)
			)
		)
		(fp_text user "License: Apache-2.0"
			(at -0.4 -5.101 0)
			(layer "B.Fab")
			(effects
				(font
					(size 0.7 0.7)
					(thickness 0.15)
				)
				(justify left bottom mirror)
			)
		)
		(fp_text user "Author: Antmicro"
			(at -0.4 -3.901 0)
			(layer "B.Fab")
			(effects
				(font
					(size 0.7 0.7)
					(thickness 0.15)
				)
				(justify left bottom mirror)
			)
		)
		(pad "1" smd circle
			(at 0 0 180)
			(size 0.75 0.75)
			(layers "B.Cu" "B.Mask")
			(net 1 "GND")
			(pinfunction "1")
			(pintype "passive")
		)
	)
	(footprint "antmicro-footprints:R_0402_1005Metric"
		(layer "B.Cu")
		(at 156.972494 96.375897 90)
		(descr "Resistor SMD 0402")
		(tags "resistor SMD 0402")
		(property "Reference" "R70"
			(at 5.74043 0.41018 90)
			(layer "B.SilkS")
			(effects
				(font
					(size 0.7 0.7)
					(thickness 0.15)
				)
				(justify right bottom mirror)
			)
		)
		(property "Value" "R_200R_0402"
			(at -1.011843 -1.772046 90)
			(layer "B.Fab")
			(effects
				(font
					(size 0.7 0.7)
					(thickness 0.15)
				)
				(justify right bottom mirror)
			)
		)
		(property "Datasheet" "https://www.bourns.com/docs/product-datasheets/cr.pdf"
			(at 0 0 90)
			(layer "F.Fab")
			(hide yes)
			(effects
				(font
					(size 1.27 1.27)
					(thickness 0.15)
				)
			)
		)
		(property "Description" "SMD Chip Resistor, 200 ohm, ± 1%, 62.5 mW, 0402 [1005 Metric], Thick Film, General Purpose"
			(at 0 0 90)
			(layer "F.Fab")
			(hide yes)
			(effects
				(font
					(size 1.27 1.27)
					(thickness 0.15)
				)
			)
		)
		(property "Author" "Antmicro"
			(at 336.245363 52.201432 135)
			(layer "B.Fab")
			(hide yes)
			(effects
				(font
					(size 1 1)
					(thickness 0.15)
				)
				(justify mirror)
			)
		)
		(property "License" "Apache-2.0"
			(at 336.245363 52.201432 135)
			(layer "B.Fab")
			(hide yes)
			(effects
				(font
					(size 1 1)
					(thickness 0.15)
				)
				(justify mirror)
			)
		)
		(property "MPN" "CR0402-FX-2000GLF"
			(at 336.245363 52.201432 135)
			(layer "B.Fab")
			(hide yes)
			(effects
				(font
					(size 1 1)
					(thickness 0.15)
				)
				(justify mirror)
			)
		)
		(property "Manufacturer" "Bourns"
			(at 336.245363 52.201432 135)
			(layer "B.Fab")
			(hide yes)
			(effects
				(font
					(size 1 1)
					(thickness 0.15)
				)
				(justify mirror)
			)
		)
		(property "Public" ""
			(at 336.245363 52.201432 135)
			(layer "B.Fab")
			(hide yes)
			(effects
				(font
					(size 1 1)
					(thickness 0.15)
				)
				(justify mirror)
			)
		)
		(property "Tolerance" "1%"
			(at 336.245363 52.201432 135)
			(layer "B.Fab")
			(hide yes)
			(effects
				(font
					(size 1 1)
					(thickness 0.15)
				)
				(justify mirror)
			)
		)
		(property "Val" "200R"
			(at 336.245363 52.201432 135)
			(layer "B.Fab")
			(hide yes)
			(effects
				(font
					(size 1 1)
					(thickness 0.15)
				)
				(justify mirror)
			)
		)
		(sheetname "/Connectors/")
		(sheetfile "connectors.kicad_sch")
		(attr smd)
		(fp_poly
			(pts
				(xy -0.925 0.47) (xy 0.925 0.47) (xy 0.925 -0.47) (xy -0.925 -0.47)
			)
			(stroke
				(width 0.05)
				(type default)
			)
			(fill no)
			(layer "B.CrtYd")
		)
		(fp_poly
			(pts
				(xy -0.5 0.25) (xy 0.5 0.25) (xy 0.5 -0.25) (xy -0.5 -0.25)
			)
			(stroke
				(width 0.15)
				(type solid)
			)
			(fill no)
			(layer "B.Fab")
		)
		(pad "1" smd roundrect
			(at -0.48 0 90)
			(size 0.59 0.64)
			(layers "B.Cu" "B.Mask" "B.Paste")
			(roundrect_rratio 0.25)
			(net 1 "GND")
			(pintype "passive")
		)
		(pad "2" smd roundrect
			(at 0.48 0 90)
			(size 0.59 0.64)
			(layers "B.Cu" "B.Mask" "B.Paste")
			(roundrect_rratio 0.25)
			(net 65 "Net-(D12-C)")
			(pintype "passive")
		)
	)
	(footprint "antmicro-footprints:R_0402_1005Metric"
		(layer "B.Cu")
		(at 133.791 86.318 180)
		(descr "Resistor SMD 0402")
		(tags "resistor SMD 0402")
		(property "Reference" "R57"
			(at -1.083109 0.379967 0)
			(layer "B.SilkS")
			(effects
				(font
					(size 0.7 0.7)
					(thickness 0.15)
				)
				(justify left bottom mirror)
			)
		)
		(property "Value" "R_0R_0402"
			(at -1.011843 -1.772047 0)
			(layer "B.Fab")
			(effects
				(font
					(size 0.7 0.7)
					(thickness 0.15)
				)
				(justify left bottom mirror)
			)
		)
		(property "Datasheet" "https://industrial.panasonic.com/cdbs/www-data/pdf/RDA0000/AOA0000C301.pdf"
			(at 0 0 180)
			(layer "F.Fab")
			(hide yes)
			(effects
				(font
					(size 1.27 1.27)
					(thickness 0.15)
				)
			)
		)
		(property "Description" "SMD Chip Resistor, Jumper, 0 ohm, 100 mW, 0402 [1005 Metric], Thick Film, General Purpose"
			(at 0 0 180)
			(layer "F.Fab")
			(hide yes)
			(effects
				(font
					(size 1.27 1.27)
					(thickness 0.15)
				)
			)
		)
		(property "Author" "Antmicro"
			(at 267.582 172.636 0)
			(layer "B.Fab")
			(hide yes)
			(effects
				(font
					(size 1 1)
					(thickness 0.15)
				)
				(justify mirror)
			)
		)
		(property "Current" "1A"
			(at 267.582 172.636 0)
			(layer "B.Fab")
			(hide yes)
			(effects
				(font
					(size 1 1)
					(thickness 0.15)
				)
				(justify mirror)
			)
		)
		(property "License" "Apache-2.0"
			(at 267.582 172.636 0)
			(layer "B.Fab")
			(hide yes)
			(effects
				(font
					(size 1 1)
					(thickness 0.15)
				)
				(justify mirror)
			)
		)
		(property "MPN" "ERJ2GE0R00X"
			(at 267.582 172.636 0)
			(layer "B.Fab")
			(hide yes)
			(effects
				(font
					(size 1 1)
					(thickness 0.15)
				)
				(justify mirror)
			)
		)
		(property "Manufacturer" "Panasonic"
			(at 267.582 172.636 0)
			(layer "B.Fab")
			(hide yes)
			(effects
				(font
					(size 1 1)
					(thickness 0.15)
				)
				(justify mirror)
			)
		)
		(property "Tolerance" ""
			(at 267.582 172.636 0)
			(layer "B.Fab")
			(hide yes)
			(effects
				(font
					(size 1 1)
					(thickness 0.15)
				)
				(justify mirror)
			)
		)
		(property "Val" "0R"
			(at 267.582 172.636 0)
			(layer "B.Fab")
			(hide yes)
			(effects
				(font
					(size 1 1)
					(thickness 0.15)
				)
				(justify mirror)
			)
		)
		(sheetname "/Deserializer/")
		(sheetfile "deserializer.kicad_sch")
		(attr smd)
		(fp_rect
			(start -0.925 0.47)
			(end 0.925 -0.47)
			(stroke
				(width 0.05)
				(type default)
			)
			(fill no)
			(layer "B.CrtYd")
		)
		(fp_rect
			(start -0.5 0.25)
			(end 0.5 -0.25)
			(stroke
				(width 0.15)
				(type solid)
			)
			(fill no)
			(layer "B.Fab")
		)
		(pad "1" smd roundrect
			(at -0.48 0 180)
			(size 0.59 0.64)
			(layers "B.Cu" "B.Mask" "B.Paste")
			(roundrect_rratio 0.25)
			(net 29 "/Deserializer/VTERM")
			(pintype "passive")
		)
		(pad "2" smd roundrect
			(at 0.48 0 180)
			(size 0.59 0.64)
			(layers "B.Cu" "B.Mask" "B.Paste")
			(roundrect_rratio 0.25)
			(net 73 "+1V2")
			(pintype "passive")
		)
	)
	(footprint "antmicro-footprints:C_0402_1005Metric"
		(layer "B.Cu")
		(at 152.146 84.074 135)
		(descr "Capacitor SMD 0402")
		(tags "capacitor SMD 0402")
		(property "Reference" "C40"
			(at -1.00197 -1.314713 315)
			(unlocked yes)
			(layer "B.SilkS")
			(effects
				(font
					(size 0.7 0.7)
					(thickness 0.15)
				)
				(justify right bottom mirror)
			)
		)
		(property "Value" "C_100n_0402"
			(at -1.022927 -2.155213 135)
			(layer "B.Fab")
			(effects
				(font
					(size 0.7 0.7)
					(thickness 0.15)
				)
				(justify right bottom mirror)
			)
		)
		(property "Datasheet" "https://www.murata.com/products/productdetail?partno=GRM155R61H104KE14%23"
			(at 0 0 135)
			(layer "F.Fab")
			(hide yes)
			(effects
				(font
					(size 1.27 1.27)
					(thickness 0.15)
				)
			)
		)
		(property "Description" "SMD Multilayer Ceramic Capacitor, 0.1 µF, 50 V, 0402 [1005 Metric], ± 10%, X5R, GRM Series"
			(at 0 0 135)
			(layer "F.Fab")
			(hide yes)
			(effects
				(font
					(size 1.27 1.27)
					(thickness 0.15)
				)
			)
		)
		(property "Author" "Antmicro"
			(at 319.178764 35.939827 0)
			(layer "B.Fab")
			(hide yes)
			(effects
				(font
					(size 1 1)
					(thickness 0.15)
				)
				(justify mirror)
			)
		)
		(property "Dielectric" "X5R"
			(at 319.178764 35.939827 0)
			(layer "B.Fab")
			(hide yes)
			(effects
				(font
					(size 1 1)
					(thickness 0.15)
				)
				(justify mirror)
			)
		)
		(property "License" "Apache-2.0"
			(at 319.178764 35.939827 0)
			(layer "B.Fab")
			(hide yes)
			(effects
				(font
					(size 1 1)
					(thickness 0.15)
				)
				(justify mirror)
			)
		)
		(property "MPN" "GRM155R61H104KE14D"
			(at 319.178764 35.939827 0)
			(layer "B.Fab")
			(hide yes)
			(effects
				(font
					(size 1 1)
					(thickness 0.15)
				)
				(justify mirror)
			)
		)
		(property "Manufacturer" "Murata"
			(at 319.178764 35.939827 0)
			(layer "B.Fab")
			(hide yes)
			(effects
				(font
					(size 1 1)
					(thickness 0.15)
				)
				(justify mirror)
			)
		)
		(property "Val" "100n"
			(at 319.178764 35.939827 0)
			(layer "B.Fab")
			(hide yes)
			(effects
				(font
					(size 1 1)
					(thickness 0.15)
				)
				(justify mirror)
			)
		)
		(property "Voltage" "50V"
			(at 319.178764 35.939827 0)
			(layer "B.Fab")
			(hide yes)
			(effects
				(font
					(size 1 1)
					(thickness 0.15)
				)
				(justify mirror)
			)
		)
		(sheetname "/Deserializer/")
		(sheetfile "deserializer.kicad_sch")
		(attr smd)
		(fp_poly
			(pts
				(xy -0.925 0.47) (xy 0.925 0.47) (xy 0.925 -0.47) (xy -0.925 -0.47)
			)
			(stroke
				(width 0.05)
				(type default)
			)
			(fill no)
			(layer "B.CrtYd")
		)
		(fp_line
			(start 0.504 -0.248)
			(end 0.504 0.25)
			(stroke
				(width 0.15)
				(type solid)
			)
			(layer "B.Fab")
		)
		(fp_line
			(start 0.504 0.25)
			(end -0.494 0.25)
			(stroke
				(width 0.15)
				(type solid)
			)
			(layer "B.Fab")
		)
		(fp_line
			(start -0.494 -0.248)
			(end 0.504 -0.248)
			(stroke
				(width 0.15)
				(type solid)
			)
			(layer "B.Fab")
		)
		(fp_line
			(start -0.494 0.25)
			(end -0.494 -0.248)
			(stroke
				(width 0.15)
				(type solid)
			)
			(layer "B.Fab")
		)
		(pad "1" smd roundrect
			(at -0.48 0 135)
			(size 0.59 0.64)
			(layers "B.Cu" "B.Mask" "B.Paste")
			(roundrect_rratio 0.25)
			(net 1 "GND")
			(pintype "passive")
		)
		(pad "2" smd roundrect
			(at 0.48 0 135)
			(size 0.59 0.64)
			(layers "B.Cu" "B.Mask" "B.Paste")
			(roundrect_rratio 0.25)
			(net 27 "/Deserializer/VDD")
			(pintype "passive")
		)
	)
	(footprint "antmicro-footprints:TP_SMD_0.75mm"
		(layer "B.Cu")
		(at 152.4 97.89 180)
		(property "Reference" "TP22"
			(at 0 0.6 0)
			(layer "B.SilkS")
			(hide yes)
			(effects
				(font
					(size 0.7 0.7)
					(thickness 0.15)
				)
				(justify left bottom mirror)
			)
		)
		(property "Value" "TP_0.75mm_SMD"
			(at 0 -1.2 0)
			(layer "B.Fab")
			(effects
				(font
					(size 0.7 0.7)
					(thickness 0.15)
				)
				(justify left bottom mirror)
			)
		)
		(property "Description" "SMT test point"
			(at 0 0 0)
			(layer "B.Fab")
			(hide yes)
			(effects
				(font
					(size 1.27 1.27)
					(thickness 0.15)
				)
				(justify mirror)
			)
		)
		(property "MPN" ""
			(at 0 0 0)
			(unlocked yes)
			(layer "B.Fab")
			(hide yes)
			(effects
				(font
					(size 1 1)
					(thickness 0.15)
				)
				(justify mirror)
			)
		)
		(property "Manufacturer" ""
			(at 0 0 0)
			(unlocked yes)
			(layer "B.Fab")
			(hide yes)
			(effects
				(font
					(size 1 1)
					(thickness 0.15)
				)
				(justify mirror)
			)
		)
		(property "Author" "Antmicro"
			(at 0 0 0)
			(unlocked yes)
			(layer "B.Fab")
			(hide yes)
			(effects
				(font
					(size 1 1)
					(thickness 0.15)
				)
				(justify mirror)
			)
		)
		(property "License" "Apache-2.0"
			(at 0 0 0)
			(unlocked yes)
			(layer "B.Fab")
			(hide yes)
			(effects
				(font
					(size 1 1)
					(thickness 0.15)
				)
				(justify mirror)
			)
		)
		(sheetname "/Connectors/")
		(sheetfile "connectors.kicad_sch")
		(attr exclude_from_pos_files)
		(fp_circle
			(center 0 0)
			(end 0.475 0)
			(stroke
				(width 0.05)
				(type default)
			)
			(fill no)
			(layer "B.CrtYd")
		)
		(fp_text user "License: Apache-2.0"
			(at -0.4 -5.101 0)
			(layer "B.Fab")
			(effects
				(font
					(size 0.7 0.7)
					(thickness 0.15)
				)
				(justify left bottom mirror)
			)
		)
		(fp_text user "Author: Antmicro"
			(at -0.4 -3.901 0)
			(layer "B.Fab")
			(effects
				(font
					(size 0.7 0.7)
					(thickness 0.15)
				)
				(justify left bottom mirror)
			)
		)
		(fp_text user "${REFERENCE}"
			(at -0.4 -2.7 0)
			(layer "B.Fab")
			(effects
				(font
					(size 0.7 0.7)
					(thickness 0.15)
				)
				(justify left bottom mirror)
			)
		)
		(pad "1" smd circle
			(at 0 0 180)
			(size 0.75 0.75)
			(layers "B.Cu" "B.Mask")
			(net 2 "/Connectors/DC_UNFUSED")
			(pinfunction "1")
			(pintype "passive")
		)
	)
	(footprint "antmicro-footprints:TP_SMD_0.75mm"
		(layer "B.Cu")
		(at 132.2 84.8 180)
		(property "Reference" "TP28"
			(at 0 0.6 0)
			(layer "B.SilkS")
			(hide yes)
			(effects
				(font
					(size 0.7 0.7)
					(thickness 0.15)
				)
				(justify left bottom mirror)
			)
		)
		(property "Value" "TP_0.75mm_SMD"
			(at 0 -1.2 0)
			(layer "B.Fab")
			(effects
				(font
					(size 0.7 0.7)
					(thickness 0.15)
				)
				(justify left bottom mirror)
			)
		)
		(property "Description" "SMT test point"
			(at 0 0 0)
			(layer "B.Fab")
			(hide yes)
			(effects
				(font
					(size 1.27 1.27)
					(thickness 0.15)
				)
				(justify mirror)
			)
		)
		(property "MPN" ""
			(at 0 0 0)
			(unlocked yes)
			(layer "B.Fab")
			(hide yes)
			(effects
				(font
					(size 1 1)
					(thickness 0.15)
				)
				(justify mirror)
			)
		)
		(property "Manufacturer" ""
			(at 0 0 0)
			(unlocked yes)
			(layer "B.Fab")
			(hide yes)
			(effects
				(font
					(size 1 1)
					(thickness 0.15)
				)
				(justify mirror)
			)
		)
		(property "Author" "Antmicro"
			(at 0 0 0)
			(unlocked yes)
			(layer "B.Fab")
			(hide yes)
			(effects
				(font
					(size 1 1)
					(thickness 0.15)
				)
				(justify mirror)
			)
		)
		(property "License" "Apache-2.0"
			(at 0 0 0)
			(unlocked yes)
			(layer "B.Fab")
			(hide yes)
			(effects
				(font
					(size 1 1)
					(thickness 0.15)
				)
				(justify mirror)
			)
		)
		(sheetname "/Power/")
		(sheetfile "power.kicad_sch")
		(attr exclude_from_pos_files)
		(fp_circle
			(center 0 0)
			(end 0.475 0)
			(stroke
				(width 0.05)
				(type default)
			)
			(fill no)
			(layer "B.CrtYd")
		)
		(fp_text user "${REFERENCE}"
			(at -0.4 -2.7 0)
			(layer "B.Fab")
			(effects
				(font
					(size 0.7 0.7)
					(thickness 0.15)
				)
				(justify left bottom mirror)
			)
		)
		(fp_text user "Author: Antmicro"
			(at -0.4 -3.901 0)
			(layer "B.Fab")
			(effects
				(font
					(size 0.7 0.7)
					(thickness 0.15)
				)
				(justify left bottom mirror)
			)
		)
		(fp_text user "License: Apache-2.0"
			(at -0.4 -5.101 0)
			(layer "B.Fab")
			(effects
				(font
					(size 0.7 0.7)
					(thickness 0.15)
				)
				(justify left bottom mirror)
			)
		)
		(pad "1" smd circle
			(at 0 0 180)
			(size 0.75 0.75)
			(layers "B.Cu" "B.Mask")
			(net 3 "+1V8")
			(pinfunction "1")
			(pintype "passive")
		)
	)
)
